# S9S_MB_2U (Grand Teton) — schematic netlist excerpt (pin names and nets, part order shuffled) for the footprints in the layout excerpt that follows; sources: Cadence DE-HDL packaged netlist, KiCad conversion of 03242023_DA0F0TMBIJ0_F0T_Motherboard_J_brd_V01_OCP.brd

R501  Q_RES  33.2 1% CHIP  pkg 0402LF  page 185 : A = SPI_PCH_CS0_R_N ; B = SPI_SYS_CS0_N
PC408_P1_2  Q_CAP  1UF 16V 10% X6S  pkg C0402  page 289 : A = PVCCFA_EHV_FIVRA_CPU1 ; B = GND

(kicad_pcb
	(version 20260206)
	(generator "pcbnew")
	(generator_version "10.0")
	(general
		(thickness 1.6)
		(legacy_teardrops no)
	)
	(paper "A4")
	(title_block
		(title "03242023_DA0F0TMBIJ0_F0T_Motherboard_J_brd_V01_OCP.brd")
		(comment 1 "Grand Teton / footprints 4918-4919 of 6105")
	)
	(layers
		(0 "F.Cu" signal "TOP")
		(4 "In1.Cu" signal "GND")
		(6 "In2.Cu" signal "IN1")
		(8 "In3.Cu" signal "GND1")
		(10 "In4.Cu" signal "IN2")
		(12 "In5.Cu" signal "GND2")
		(14 "In6.Cu" signal "IN3")
		(16 "In7.Cu" signal "GND3")
		(18 "In8.Cu" signal "VCC")
		(20 "In9.Cu" signal "VCC1")
		(22 "In10.Cu" signal "GND4")
		(24 "In11.Cu" signal "IN4")
		(26 "In12.Cu" signal "GND5")
		(28 "In13.Cu" signal "IN5")
		(30 "In14.Cu" signal "GND6")
		(32 "In15.Cu" signal "IN6")
		(34 "In16.Cu" signal "GND7")
		(2 "B.Cu" signal "BOTTOM")
		(9 "F.Adhes" user "F.Adhesive")
		(11 "B.Adhes" user "B.Adhesive")
		(13 "F.Paste" user "Package Geometry/Pastemask Top")
		(15 "B.Paste" user "Package Geometry/Pastemask Bottom")
		(5 "F.SilkS" user "Ref Des/Silkscreen Top")
		(7 "B.SilkS" user "Ref Des/Silkscreen Bottom")
		(1 "F.Mask" user "Board Geometry/Soldermask Top")
		(3 "B.Mask" user "Board Geometry/Soldermask Bottom")
		(17 "Dwgs.User" user "User.Drawings")
		(19 "Cmts.User" user "User.Comments")
		(21 "Eco1.User" user "User.Eco1")
		(23 "Eco2.User" user "User.Eco2")
		(25 "Edge.Cuts" user "Board Geometry/Outline")
		(27 "Margin" user)
		(31 "F.CrtYd" user "Package Geometry/Place Bound Top")
		(29 "B.CrtYd" user "Package Geometry/Place Bound Bottom")
		(35 "F.Fab" user "Ref Des/Assembly Top")
		(33 "B.Fab" user "Ref Des/Assembly Bottom")
	)
	(footprint ""
		(layer "B.Cu")
		(at 332.7781 -33.173416 90)
		(property "Reference" "R501"
			(at 0 0 90)
			(layer "B.SilkS")
			(hide yes)
			(effects
				(font
					(size 1.27 1.27)
				)
				(justify mirror)
			)
		)
		(property "Value" ""
			(at 0 0 90)
			(layer "B.Fab")
			(effects
				(font
					(size 1.27 1.27)
				)
				(justify mirror)
			)
		)
		(duplicate_pad_numbers_are_jumpers no)
		(fp_line
			(start 0.7874 -0.4064)
			(end -0.7874 -0.4064)
			(stroke
				(width 0.1524)
				(type default)
			)
			(layer "B.SilkS")
		)
		(fp_line
			(start -0.7874 -0.4064)
			(end -0.7874 0.4064)
			(stroke
				(width 0.1524)
				(type default)
			)
			(layer "B.SilkS")
		)
		(fp_line
			(start 0.7874 0.4064)
			(end 0.7874 -0.4064)
			(stroke
				(width 0.1524)
				(type default)
			)
			(layer "B.SilkS")
		)
		(fp_line
			(start -0.7874 0.4064)
			(end 0.7874 0.4064)
			(stroke
				(width 0.1524)
				(type default)
			)
			(layer "B.SilkS")
		)
		(fp_line
			(start 0.67945 -0.305054)
			(end 0.12065 -0.305054)
			(stroke
				(width 0.1)
				(type default)
			)
			(layer "B.Fab")
		)
		(fp_line
			(start 0.12065 -0.305054)
			(end 0.12065 -0.2794)
			(stroke
				(width 0.1)
				(type default)
			)
			(layer "B.Fab")
		)
		(fp_line
			(start -0.12065 -0.3048)
			(end -0.67945 -0.3048)
			(stroke
				(width 0.1)
				(type default)
			)
			(layer "B.Fab")
		)
		(fp_line
			(start -0.67945 -0.3048)
			(end -0.67945 0.3048)
			(stroke
				(width 0.1)
				(type default)
			)
			(layer "B.Fab")
		)
		(fp_line
			(start 0.12065 -0.2794)
			(end -0.12065 -0.2794)
			(stroke
				(width 0.1)
				(type default)
			)
			(layer "B.Fab")
		)
		(fp_line
			(start -0.12065 -0.2794)
			(end -0.12065 -0.3048)
			(stroke
				(width 0.1)
				(type default)
			)
			(layer "B.Fab")
		)
		(fp_line
			(start 0.12065 0.2794)
			(end 0.12065 0.3048)
			(stroke
				(width 0.1)
				(type default)
			)
			(layer "B.Fab")
		)
		(fp_line
			(start -0.120396 0.2794)
			(end 0.12065 0.2794)
			(stroke
				(width 0.1)
				(type default)
			)
			(layer "B.Fab")
		)
		(fp_line
			(start 0.67945 0.3048)
			(end 0.67945 -0.305054)
			(stroke
				(width 0.1)
				(type default)
			)
			(layer "B.Fab")
		)
		(fp_line
			(start 0.12065 0.3048)
			(end 0.67945 0.3048)
			(stroke
				(width 0.1)
				(type default)
			)
			(layer "B.Fab")
		)
		(fp_line
			(start -0.120396 0.3048)
			(end -0.120396 0.2794)
			(stroke
				(width 0.1)
				(type default)
			)
			(layer "B.Fab")
		)
		(fp_line
			(start -0.67945 0.3048)
			(end -0.120396 0.3048)
			(stroke
				(width 0.1)
				(type default)
			)
			(layer "B.Fab")
		)
		(pad "1" smd circle
			(at 0.40005 0 270)
			(size 0 0)
			(layers "B.Cu" "B.Mask" "B.Paste")
			(net "SPI_PCH_CS0_R_N")
		)
		(pad "2" smd circle
			(at -0.40005 0 270)
			(size 0 0)
			(layers "B.Cu" "B.Mask" "B.Paste")
			(net "SPI_SYS_CS0_N")
		)
	)
	(footprint ""
		(layer "B.Cu")
		(at 54.50332 -344.727276 -90)
		(property "Reference" "PC408_P1_2"
			(at 0 0 90)
			(layer "B.SilkS")
			(hide yes)
			(effects
				(font
					(size 1.27 1.27)
				)
				(justify mirror)
			)
		)
		(property "Value" ""
			(at 0 0 90)
			(layer "B.Fab")
			(effects
				(font
					(size 1.27 1.27)
				)
				(justify mirror)
			)
		)
		(duplicate_pad_numbers_are_jumpers no)
		(fp_line
			(start -0.7874 0.4064)
			(end 0.7874 0.4064)
			(stroke
				(width 0.1524)
				(type default)
			)
			(layer "B.SilkS")
		)
		(fp_line
			(start 0.7874 0.4064)
			(end 0.7874 -0.4064)
			(stroke
				(width 0.1524)
				(type default)
			)
			(layer "B.SilkS")
		)
		(fp_line
			(start -0.7874 -0.4064)
			(end -0.7874 0.4064)
			(stroke
				(width 0.1524)
				(type default)
			)
			(layer "B.SilkS")
		)
		(fp_line
			(start 0.7874 -0.4064)
			(end -0.7874 -0.4064)
			(stroke
				(width 0.1524)
				(type default)
			)
			(layer "B.SilkS")
		)
		(fp_line
			(start -0.67945 0.3048)
			(end -0.120396 0.3048)
			(stroke
				(width 0.1)
				(type default)
			)
			(layer "B.Fab")
		)
		(fp_line
			(start -0.120396 0.3048)
			(end -0.120396 0.2794)
			(stroke
				(width 0.1)
				(type default)
			)
			(layer "B.Fab")
		)
		(fp_line
			(start 0.12065 0.3048)
			(end 0.67945 0.3048)
			(stroke
				(width 0.1)
				(type default)
			)
			(layer "B.Fab")
		)
		(fp_line
			(start 0.67945 0.3048)
			(end 0.67945 -0.305054)
			(stroke
				(width 0.1)
				(type default)
			)
			(layer "B.Fab")
		)
		(fp_line
			(start -0.120396 0.2794)
			(end 0.12065 0.2794)
			(stroke
				(width 0.1)
				(type default)
			)
			(layer "B.Fab")
		)
		(fp_line
			(start 0.12065 0.2794)
			(end 0.12065 0.3048)
			(stroke
				(width 0.1)
				(type default)
			)
			(layer "B.Fab")
		)
		(fp_line
			(start -0.12065 -0.2794)
			(end -0.12065 -0.3048)
			(stroke
				(width 0.1)
				(type default)
			)
			(layer "B.Fab")
		)
		(fp_line
			(start 0.12065 -0.2794)
			(end -0.12065 -0.2794)
			(stroke
				(width 0.1)
				(type default)
			)
			(layer "B.Fab")
		)
		(fp_line
			(start -0.67945 -0.3048)
			(end -0.67945 0.3048)
			(stroke
				(width 0.1)
				(type default)
			)
			(layer "B.Fab")
		)
		(fp_line
			(start -0.12065 -0.3048)
			(end -0.67945 -0.3048)
			(stroke
				(width 0.1)
				(type default)
			)
			(layer "B.Fab")
		)
		(fp_line
			(start 0.12065 -0.305054)
			(end 0.12065 -0.2794)
			(stroke
				(width 0.1)
				(type default)
			)
			(layer "B.Fab")
		)
		(fp_line
			(start 0.67945 -0.305054)
			(end 0.12065 -0.305054)
			(stroke
				(width 0.1)
				(type default)
			)
			(layer "B.Fab")
		)
		(pad "1" smd circle
			(at 0.40005 0 90)
			(size 0 0)
			(layers "B.Cu" "B.Mask" "B.Paste")
			(net "PVCCFA_EHV_FIVRA_CPU1")
		)
		(pad "2" smd circle
			(at -0.40005 0 90)
			(size 0 0)
			(layers "B.Cu" "B.Mask" "B.Paste")
			(net "GND")
		)
	)
)
